# S9S_MB_2U (Grand Teton) — schematic netlist excerpt (pin names and nets, part order shuffled) for the footprints in the layout excerpt that follows; sources: Cadence DE-HDL packaged netlist, KiCad conversion of 03242023_DA0F0TMBIJ0_F0T_Motherboard_J_brd_V01_OCP.brd

J10  SCONN288_ADR50017P087CC  SCONN288_ADR50017-P087CC IO  pkg DDR288S_1-1VXB  page 91
  VIN_BULK0  = P12V_S3_AUX_CPU0_NVDIMM
  RFU0  = TP_CHE_CPU0_DIMM2_FRU_0
  VIN_MGMT  = P3V3_AUX
  HSCL  = I3C_SPD_DDREFGH_CPU0_LVC1_SCL_1
  HSDA  = I3C_SPD_DDREFGH_CPU0_LVC1_SDA
  VSS0  = GND
  DQ0_A  = M_E_CPU0_SA_DQ<0>
  VSS1  = GND
  DQ1_A  = M_E_CPU0_SA_DQ<1>
  VSS2  = GND
  DQS0_A_T  = M_E_CPU0_SA_DQS_DP<0>
  DQS0_A_C  = M_E_CPU0_SA_DQS_DN<0>
  VSS3  = GND
  DQ4_A  = M_E_CPU0_SA_DQ<4>
  VSS4  = GND
  DQ5_A  = M_E_CPU0_SA_DQ<5>
  VSS5  = GND
  DQ8_A  = M_E_CPU0_SA_DQ<8>
  VSS6  = GND
  DQ9_A  = M_E_CPU0_SA_DQ<9>
  VSS7  = GND
  DQS1_A_T  = M_E_CPU0_SA_DQS_DP<1>
  DQS1_A_C  = M_E_CPU0_SA_DQS_DN<1>
  VSS8  = GND
  DQ12_A  = M_E_CPU0_SA_DQ<12>
  VSS9  = GND
  DQ13_A  = M_E_CPU0_SA_DQ<13>
  VSS10  = GND
  DQ16_A  = M_E_CPU0_SA_DQ<16>
  VSS11  = GND
  DQ17_A  = M_E_CPU0_SA_DQ<17>
  VSS12  = GND
  DQS2_A_T  = M_E_CPU0_SA_DQS_DP<2>
  DQS2_A_C  = M_E_CPU0_SA_DQS_DN<2>
  VSS13  = GND
  DQ20_A  = M_E_CPU0_SA_DQ<20>
  VSS14  = GND
  DQ21_A  = M_E_CPU0_SA_DQ<21>
  VSS15  = GND
  DQ24_A  = M_E_CPU0_SA_DQ<24>
  VSS16  = GND
  DQ25_A  = M_E_CPU0_SA_DQ<25>
  VSS17  = GND
  DQS3_A_T  = M_E_CPU0_SA_DQS_DP<3>
  DQS3_A_C  = M_E_CPU0_SA_DQS_DN<3>
  VSS18  = GND
  DQ28_A  = M_E_CPU0_SA_DQ<28>
  VSS19  = GND
  DQ29_A  = M_E_CPU0_SA_DQ<29>
  VSS20  = GND
  CB0_A  = M_E_CPU0_SA_CB<0>
  VSS21  = GND
  CB1_A  = M_E_CPU0_SA_CB<1>
  VSS22  = GND
  DQS4_A_T  = M_E_CPU0_SA_DQS_DP<4>
  DQS4_A_C  = M_E_CPU0_SA_DQS_DN<4>
  VSS23  = GND
  CB4_A  = M_E_CPU0_SA_CB<4>
  VSS24  = GND
  CB5_A  = M_E_CPU0_SA_CB<5>
  VSS25  = GND
  ALERT_N  = M_E_CPU0_ALERT_N
  VSS26  = GND
  CS0_A_N  = M_E_CPU0_SA_CS_N<2>
  VSS27  = GND
  CA0_A  = M_E_CPU0_SA_CA<0>
  VSS28  = GND
  CA2_A  = M_E_CPU0_SA_CA<2>
  VSS29  = GND
  CA4_A  = M_E_CPU0_SA_CA<4>
  VSS30  = GND
  CA6_A  = M_E_CPU0_SA_CA<6>
  VSS31  = GND
  PAR_A  = M_E_CPU0_SA_PAR
  VSS32  = GND
  CA0_B  = M_E_CPU0_SB_CA<0>
  VSS33  = GND
  CA2_B  = M_E_CPU0_SB_CA<2>
  VSS34  = GND
  CA4_B  = M_E_CPU0_SB_CA<4>
  VSS35  = GND
  CA6_B  = M_E_CPU0_SB_CA<6>
  VSS36  = GND
  CS0_B_N  = M_E_CPU0_SB_CS_N<2>
  VSS37  = GND
  \lbd||rsp_a_n\  = M_E_CPU0_SA_RSP<1>
  \lbs||rsp_b_n\  = M_E_CPU0_SB_RSP<1>
  VSS38  = GND
  CB4_B  = M_E_CPU0_SB_CB<4>
  VSS39  = GND
  CB5_B  = M_E_CPU0_SB_CB<5>
  VSS40  = GND
  \dqs9_b_t||tdqs9_b_t||dbi4_b_n\  = M_E_CPU0_SB_DQS_DP<9>
  \dqs9_b_c||tdqs9_b_c\  = M_E_CPU0_SB_DQS_DN<9>
  VSS41  = GND
  CB0_B  = M_E_CPU0_SB_CB<0>
  VSS42  = GND
  CB1_B  = M_E_CPU0_SB_CB<1>
  VSS43  = GND
  DQ0_B  = M_E_CPU0_SB_DQ<0>
  VSS44  = GND
  DQ1_B  = M_E_CPU0_SB_DQ<1>
  VSS45  = GND
  DQS0_B_T  = M_E_CPU0_SB_DQS_DP<0>
  DQS0_B_C  = M_E_CPU0_SB_DQS_DN<0>
  VSS46  = GND
  DQ4_B  = M_E_CPU0_SB_DQ<4>
  VSS47  = GND
  DQ5_B  = M_E_CPU0_SB_DQ<5>
  VSS48  = GND
  DQ8_B  = M_E_CPU0_SB_DQ<8>
  VSS49  = GND
  DQ9_B  = M_E_CPU0_SB_DQ<9>
  VSS50  = GND
  DQS1_B_T  = M_E_CPU0_SB_DQS_DP<1>
  DQS1_B_C  = M_E_CPU0_SB_DQS_DN<1>
  VSS51  = GND
  DQ12_B  = M_E_CPU0_SB_DQ<12>
  VSS52  = GND
  DQ13_B  = M_E_CPU0_SB_DQ<13>
  VSS53  = GND
  DQ16_B  = M_E_CPU0_SB_DQ<16>
  VSS54  = GND
  DQ17_B  = M_E_CPU0_SB_DQ<17>
  VSS55  = GND
  DQS2_B_T  = M_E_CPU0_SB_DQS_DP<2>
  DQS2_B_C  = M_E_CPU0_SB_DQS_DN<2>
  VSS56  = GND
  DQ20_B  = M_E_CPU0_SB_DQ<20>
  VSS57  = GND
  DQ21_B  = M_E_CPU0_SB_DQ<21>
  VSS58  = GND
  DQ24_B  = M_E_CPU0_SB_DQ<24>
  VSS59  = GND
  DQ25_B  = M_E_CPU0_SB_DQ<25>
  VSS60  = GND
  DQS3_B_T  = M_E_CPU0_SB_DQS_DP<3>
  DQS3_B_C  = M_E_CPU0_SB_DQS_DN<3>
  VSS61  = GND
  DQ28_B  = M_E_CPU0_SB_DQ<28>
  VSS62  = GND
  DQ29_B  = M_E_CPU0_SB_DQ<29>
  VSS63  = GND
  RFU1  = TP_CHE_CPU0_DIMM2_FRU_1
  VIN_BULK1  = P12V_S3_AUX_CPU0_NVDIMM
  VIN_BULK2  = P12V_S3_AUX_CPU0_NVDIMM
  \pwr_good||fail_n\  = PWRGD_CHE_CPU0_DIMM2
  HSA  = PD_CHE_CPU0_DIMM2_SAA
  RFU2  = TP_CHE_CPU0_DIMM2_FRU_2
  RFU3  = TP_CHE_CPU0_DIMM2_FRU_3
  VSS64  = GND
  DQ2_A  = M_E_CPU0_SA_DQ<2>
  VSS65  = GND
  DQ3_A  = M_E_CPU0_SA_DQ<3>
  VSS66  = GND
  \dqs5_a_c||tdqs5_a_c||dqs5_a_t||tdqs5_a_t\  = M_E_CPU0_SA_DQS_DN<5>
  \dqs5_a_t||tdqs5_a_t\  = M_E_CPU0_SA_DQS_DP<5>
  VSS67  = GND
  DQ6_A  = M_E_CPU0_SA_DQ<6>
  VSS68  = GND
  DQ7_A  = M_E_CPU0_SA_DQ<7>
  VSS69  = GND
  DQ10_A  = M_E_CPU0_SA_DQ<10>
  VSS70  = GND
  DQ11_A  = M_E_CPU0_SA_DQ<11>
  VSS71  = GND
  \dqs6_a_c||tdqs6_a_c||dqs6_a_t||tdqs6_a_t\  = M_E_CPU0_SA_DQS_DN<6>
  \dqs6_a_t||tdqs6_a_t\  = M_E_CPU0_SA_DQS_DP<6>
  VSS72  = GND
  DQ14_A  = M_E_CPU0_SA_DQ<14>
  VSS73  = GND
  DQ15_A  = M_E_CPU0_SA_DQ<15>
  VSS74  = GND
  DQ18_A  = M_E_CPU0_SA_DQ<18>
  VSS75  = GND
  DQ19_A  = M_E_CPU0_SA_DQ<19>
  VSS76  = GND
  \dqs7_a_c||tdqs7_a_c\  = M_E_CPU0_SA_DQS_DN<7>
  \dqs7_a_t||tdqs7_a_t\  = M_E_CPU0_SA_DQS_DP<7>
  VSS77  = GND
  DQ22_A  = M_E_CPU0_SA_DQ<22>
  VSS78  = GND
  DQ23_A  = M_E_CPU0_SA_DQ<23>
  VSS79  = GND
  DQ26_A  = M_E_CPU0_SA_DQ<26>
  VSS80  = GND
  DQ27_A  = M_E_CPU0_SA_DQ<27>
  VSS81  = GND
  \dqs8_a_c||tdqs8_a_c\  = M_E_CPU0_SA_DQS_DN<8>
  \dqs8_a_t||tdqs8_a_t\  = M_E_CPU0_SA_DQS_DP<8>
  VSS82  = GND
  DQ30_A  = M_E_CPU0_SA_DQ<30>
  VSS83  = GND
  DQ31_A  = M_E_CPU0_SA_DQ<31>
  VSS84  = GND
  CB2_A  = M_E_CPU0_SA_CB<2>
  VSS85  = GND
  CB3_A  = M_E_CPU0_SA_CB<3>
  VSS86  = GND
  \dqs9_a_c||tdqs9_a_c\  = M_E_CPU0_SA_DQS_DN<9>
  \dqs9_a_t||tdqs9_a_t\  = M_E_CPU0_SA_DQS_DP<9>
  VSS87  = GND
  CB6_A  = M_E_CPU0_SA_CB<6>
  VSS88  = GND
  CB7_A  = M_E_CPU0_SA_CB<7>
  VSS89  = GND
  RESET_N  = RST_M_EF_CPU0_FPGA_N
  VSS90  = GND
  CS1_A_N  = M_E_CPU0_SA_CS_N<3>
  VSS91  = GND
  CA1_A  = M_E_CPU0_SA_CA<1>
  VSS92  = GND
  CA3_A  = M_E_CPU0_SA_CA<3>
  VSS93  = GND
  CA5_A  = M_E_CPU0_SA_CA<5>
  VSS94  = GND
  CK_T  = M_E_CPU0_CLK_DP<1>
  CK_C  = M_E_CPU0_CLK_DN<1>
  VSS95  = GND
  RFU4  = TP_CHE_CPU0_DIMM2_FRU_4
  CA1_B  = M_E_CPU0_SB_CA<1>
  VSS96  = GND
  CA3_B  = M_E_CPU0_SB_CA<3>
  VSS97  = GND
  CA5_B  = M_E_CPU0_SB_CA<5>
  VSS98  = GND
  PAR_B  = M_E_CPU0_SB_PAR
  VSS99  = GND
  CS1_B_N  = M_E_CPU0_SB_CS_N<3>
  VSS100  = GND
  RFU5  = TP_CHE_CPU0_DIMM2_FRU_5
  RFU6  = TP_CHE_CPU0_DIMM2_FRU_6
  VSS101  = GND
  CB6_B  = M_E_CPU0_SB_CB<6>
  VSS102  = GND
  CB7_B  = M_E_CPU0_SB_CB<7>
  VSS103  = GND
  DQS4_B_C  = M_E_CPU0_SB_DQS_DN<4>
  DQS4_B_T  = M_E_CPU0_SB_DQS_DP<4>
  VSS104  = GND
  CB2_B  = M_E_CPU0_SB_CB<2>
  VSS105  = GND
  CB3_B  = M_E_CPU0_SB_CB<3>
  VSS106  = GND
  DQ2_B  = M_E_CPU0_SB_DQ<2>
  VSS107  = GND
  DQ3_B  = M_E_CPU0_SB_DQ<3>
  VSS108  = GND
  \dqs5_b_c||tdqs5_b_c\  = M_E_CPU0_SB_DQS_DN<5>
  \dqs5_b_t||tdqs5_b_t\  = M_E_CPU0_SB_DQS_DP<5>
  VSS109  = GND
  DQ6_B  = M_E_CPU0_SB_DQ<6>
  VSS110  = GND
  DQ7_B  = M_E_CPU0_SB_DQ<7>
  VSS111  = GND
  DQ10_B  = M_E_CPU0_SB_DQ<10>
  VSS112  = GND
  DQ11_B  = M_E_CPU0_SB_DQ<11>
  VSS113  = GND
  \dqs6_b_c||tdqs6_b_c\  = M_E_CPU0_SB_DQS_DN<6>
  \dqs6_b_t||tdqs6_b_t\  = M_E_CPU0_SB_DQS_DP<6>
  VSS114  = GND
  DQ14_B  = M_E_CPU0_SB_DQ<14>
  VSS115  = GND
  DQ15_B  = M_E_CPU0_SB_DQ<15>
  VSS116  = GND
  DQ18_B  = M_E_CPU0_SB_DQ<18>
  VSS117  = GND
  DQ19_B  = M_E_CPU0_SB_DQ<19>
  VSS118  = GND
  \dqs7_b_c||tdqs7_b_c\  = M_E_CPU0_SB_DQS_DN<7>
  \dqs7_b_t||tdqs7_b_t\  = M_E_CPU0_SB_DQS_DP<7>
  VSS119  = GND
  DQ22_B  = M_E_CPU0_SB_DQ<22>
  VSS120  = GND
  DQ23_B  = M_E_CPU0_SB_DQ<23>
  VSS121  = GND
  DQ26_B  = M_E_CPU0_SB_DQ<26>
  VSS122  = GND
  DQ27_B  = M_E_CPU0_SB_DQ<27>
  VSS123  = GND
  \dqs8_b_c||tdqs8_b_c\  = M_E_CPU0_SB_DQS_DN<8>
  \dqs8_b_t||tdqs8_b_t\  = M_E_CPU0_SB_DQS_DP<8>
  VSS124  = GND
  DQ30_B  = M_E_CPU0_SB_DQ<30>
  VSS125  = GND
  DQ31_B  = M_E_CPU0_SB_DQ<31>
  VSS126  = GND
  G1  = GND
  G2  = GND
  G3  = GND

(kicad_pcb
	(version 20260206)
	(generator "pcbnew")
	(generator_version "10.0")
	(general
		(thickness 1.6)
		(legacy_teardrops no)
	)
	(paper "A4")
	(title_block
		(title "03242023_DA0F0TMBIJ0_F0T_Motherboard_J_brd_V01_OCP.brd")
		(comment 1 "Grand Teton / footprint 1607 of 6105 (J10), pads 46-91 of 291")
	)
	(layers
		(0 "F.Cu" signal "TOP")
		(4 "In1.Cu" signal "GND")
		(6 "In2.Cu" signal "IN1")
		(8 "In3.Cu" signal "GND1")
		(10 "In4.Cu" signal "IN2")
		(12 "In5.Cu" signal "GND2")
		(14 "In6.Cu" signal "IN3")
		(16 "In7.Cu" signal "GND3")
		(18 "In8.Cu" signal "VCC")
		(20 "In9.Cu" signal "VCC1")
		(22 "In10.Cu" signal "GND4")
		(24 "In11.Cu" signal "IN4")
		(26 "In12.Cu" signal "GND5")
		(28 "In13.Cu" signal "IN5")
		(30 "In14.Cu" signal "GND6")
		(32 "In15.Cu" signal "IN6")
		(34 "In16.Cu" signal "GND7")
		(2 "B.Cu" signal "BOTTOM")
		(9 "F.Adhes" user "F.Adhesive")
		(11 "B.Adhes" user "B.Adhesive")
		(13 "F.Paste" user "Package Geometry/Pastemask Top")
		(15 "B.Paste" user "Package Geometry/Pastemask Bottom")
		(5 "F.SilkS" user "Ref Des/Silkscreen Top")
		(7 "B.SilkS" user "Ref Des/Silkscreen Bottom")
		(1 "F.Mask" user "Board Geometry/Soldermask Top")
		(3 "B.Mask" user "Board Geometry/Soldermask Bottom")
		(17 "Dwgs.User" user "User.Drawings")
		(19 "Cmts.User" user "User.Comments")
		(21 "Eco1.User" user "User.Eco1")
		(23 "Eco2.User" user "User.Eco2")
		(25 "Edge.Cuts" user "Board Geometry/Outline")
		(27 "Margin" user)
		(31 "F.CrtYd" user "Package Geometry/Place Bound Top")
		(29 "B.CrtYd" user "Package Geometry/Place Bound Bottom")
		(35 "F.Fab" user "Ref Des/Assembly Top")
		(33 "B.Fab" user "Ref Des/Assembly Bottom")
	)
	(footprint ""
		(layer "F.Cu")
		(at 408.803348 -258.091686)
		(property "Reference" "J10"
			(at -3.683 -81.702148 0)
			(unlocked yes)
			(layer "F.SilkS")
			(effects
				(font
					(size 0.7874 0.5842)
					(thickness 0.1524)
				)
				(justify left)
			)
		)
		(property "Value" ""
			(at 0 0 0)
			(layer "F.Fab")
			(effects
				(font
					(size 1.27 1.27)
				)
			)
		)
		(duplicate_pad_numbers_are_jumpers no)
		(pad "46" smd rect
			(at -2.050034 -25.07488 270)
			(size 0.519938 1.4986)
			(layers "F.Cu" "F.Mask" "F.Paste")
			(net "GND")
		)
		(pad "47" smd rect
			(at -2.050034 -24.224996 270)
			(size 0.519938 1.4986)
			(layers "F.Cu" "F.Mask" "F.Paste")
			(net "M_E_CPU0_SA_DQ<28>")
		)
		(pad "48" smd rect
			(at -2.050034 -23.375112 270)
			(size 0.519938 1.4986)
			(layers "F.Cu" "F.Mask" "F.Paste")
			(net "GND")
		)
		(pad "49" smd rect
			(at -2.050034 -22.524974 270)
			(size 0.519938 1.4986)
			(layers "F.Cu" "F.Mask" "F.Paste")
			(net "M_E_CPU0_SA_DQ<29>")
		)
		(pad "50" smd rect
			(at -2.050034 -21.67509 270)
			(size 0.519938 1.4986)
			(layers "F.Cu" "F.Mask" "F.Paste")
			(net "GND")
		)
		(pad "51" smd rect
			(at -2.050034 -20.824952 270)
			(size 0.519938 1.4986)
			(layers "F.Cu" "F.Mask" "F.Paste")
			(net "M_E_CPU0_SA_CB<0>")
		)
		(pad "52" smd rect
			(at -2.050034 -19.975068 270)
			(size 0.519938 1.4986)
			(layers "F.Cu" "F.Mask" "F.Paste")
			(net "GND")
		)
		(pad "53" smd rect
			(at -2.050034 -19.12493 270)
			(size 0.519938 1.4986)
			(layers "F.Cu" "F.Mask" "F.Paste")
			(net "M_E_CPU0_SA_CB<1>")
		)
		(pad "54" smd rect
			(at -2.050034 -18.275046 270)
			(size 0.519938 1.4986)
			(layers "F.Cu" "F.Mask" "F.Paste")
			(net "GND")
		)
		(pad "55" smd rect
			(at -2.050034 -17.424908 270)
			(size 0.519938 1.4986)
			(layers "F.Cu" "F.Mask" "F.Paste")
			(net "M_E_CPU0_SA_DQS_DP<4>")
		)
		(pad "56" smd rect
			(at -2.050034 -16.575024 270)
			(size 0.519938 1.4986)
			(layers "F.Cu" "F.Mask" "F.Paste")
			(net "M_E_CPU0_SA_DQS_DN<4>")
		)
		(pad "57" smd rect
			(at -2.050034 -15.724886 270)
			(size 0.519938 1.4986)
			(layers "F.Cu" "F.Mask" "F.Paste")
			(net "GND")
		)
		(pad "58" smd rect
			(at -2.050034 -14.875002 270)
			(size 0.519938 1.4986)
			(layers "F.Cu" "F.Mask" "F.Paste")
			(net "M_E_CPU0_SA_CB<4>")
		)
		(pad "59" smd rect
			(at -2.050034 -14.025118 270)
			(size 0.519938 1.4986)
			(layers "F.Cu" "F.Mask" "F.Paste")
			(net "GND")
		)
		(pad "60" smd rect
			(at -2.050034 -13.17498 270)
			(size 0.519938 1.4986)
			(layers "F.Cu" "F.Mask" "F.Paste")
			(net "M_E_CPU0_SA_CB<5>")
		)
		(pad "61" smd rect
			(at -2.050034 -12.325096 270)
			(size 0.519938 1.4986)
			(layers "F.Cu" "F.Mask" "F.Paste")
			(net "GND")
		)
		(pad "62" smd rect
			(at -2.050034 -11.474958 270)
			(size 0.519938 1.4986)
			(layers "F.Cu" "F.Mask" "F.Paste")
			(net "M_E_CPU0_ALERT_N")
		)
		(pad "63" smd rect
			(at -2.050034 -10.625074 270)
			(size 0.519938 1.4986)
			(layers "F.Cu" "F.Mask" "F.Paste")
			(net "GND")
		)
		(pad "64" smd rect
			(at -2.050034 -9.774936 270)
			(size 0.519938 1.4986)
			(layers "F.Cu" "F.Mask" "F.Paste")
			(net "M_E_CPU0_SA_CS_N<2>")
		)
		(pad "65" smd rect
			(at -2.050034 -8.925052 270)
			(size 0.519938 1.4986)
			(layers "F.Cu" "F.Mask" "F.Paste")
			(net "GND")
		)
		(pad "66" smd rect
			(at -2.050034 -8.074914 270)
			(size 0.519938 1.4986)
			(layers "F.Cu" "F.Mask" "F.Paste")
			(net "M_E_CPU0_SA_CA<0>")
		)
		(pad "67" smd rect
			(at -2.050034 -7.22503 270)
			(size 0.519938 1.4986)
			(layers "F.Cu" "F.Mask" "F.Paste")
			(net "GND")
		)
		(pad "68" smd rect
			(at -2.050034 -6.374892 270)
			(size 0.519938 1.4986)
			(layers "F.Cu" "F.Mask" "F.Paste")
			(net "M_E_CPU0_SA_CA<2>")
		)
		(pad "69" smd rect
			(at -2.050034 -5.525008 270)
			(size 0.519938 1.4986)
			(layers "F.Cu" "F.Mask" "F.Paste")
			(net "GND")
		)
		(pad "70" smd rect
			(at -2.050034 -4.675124 270)
			(size 0.519938 1.4986)
			(layers "F.Cu" "F.Mask" "F.Paste")
			(net "M_E_CPU0_SA_CA<4>")
		)
		(pad "71" smd rect
			(at -2.050034 -3.824986 270)
			(size 0.519938 1.4986)
			(layers "F.Cu" "F.Mask" "F.Paste")
			(net "GND")
		)
		(pad "72" smd rect
			(at -2.050034 -2.975102 270)
			(size 0.519938 1.4986)
			(layers "F.Cu" "F.Mask" "F.Paste")
			(net "M_E_CPU0_SA_CA<6>")
		)
		(pad "73" smd rect
			(at -2.050034 -2.124964 270)
			(size 0.519938 1.4986)
			(layers "F.Cu" "F.Mask" "F.Paste")
			(net "GND")
		)
		(pad "74" smd rect
			(at -2.050034 -1.27508 270)
			(size 0.519938 1.4986)
			(layers "F.Cu" "F.Mask" "F.Paste")
			(net "M_E_CPU0_SA_PAR")
		)
		(pad "75" smd rect
			(at -2.050034 -0.424942 270)
			(size 0.519938 1.4986)
			(layers "F.Cu" "F.Mask" "F.Paste")
			(net "GND")
		)
		(pad "76" smd rect
			(at -2.050034 5.525008 270)
			(size 0.519938 1.4986)
			(layers "F.Cu" "F.Mask" "F.Paste")
			(net "M_E_CPU0_SB_CA<0>")
		)
		(pad "77" smd rect
			(at -2.050034 6.374892 270)
			(size 0.519938 1.4986)
			(layers "F.Cu" "F.Mask" "F.Paste")
			(net "GND")
		)
		(pad "78" smd rect
			(at -2.050034 7.22503 270)
			(size 0.519938 1.4986)
			(layers "F.Cu" "F.Mask" "F.Paste")
			(net "M_E_CPU0_SB_CA<2>")
		)
		(pad "79" smd rect
			(at -2.050034 8.074914 270)
			(size 0.519938 1.4986)
			(layers "F.Cu" "F.Mask" "F.Paste")
			(net "GND")
		)
		(pad "80" smd rect
			(at -2.050034 8.925052 270)
			(size 0.519938 1.4986)
			(layers "F.Cu" "F.Mask" "F.Paste")
			(net "M_E_CPU0_SB_CA<4>")
		)
		(pad "81" smd rect
			(at -2.050034 9.774936 270)
			(size 0.519938 1.4986)
			(layers "F.Cu" "F.Mask" "F.Paste")
			(net "GND")
		)
		(pad "82" smd rect
			(at -2.050034 10.625074 270)
			(size 0.519938 1.4986)
			(layers "F.Cu" "F.Mask" "F.Paste")
			(net "M_E_CPU0_SB_CA<6>")
		)
		(pad "83" smd rect
			(at -2.050034 11.474958 270)
			(size 0.519938 1.4986)
			(layers "F.Cu" "F.Mask" "F.Paste")
			(net "GND")
		)
		(pad "84" smd rect
			(at -2.050034 12.325096 270)
			(size 0.519938 1.4986)
			(layers "F.Cu" "F.Mask" "F.Paste")
			(net "M_E_CPU0_SB_CS_N<2>")
		)
		(pad "85" smd rect
			(at -2.050034 13.17498 270)
			(size 0.519938 1.4986)
			(layers "F.Cu" "F.Mask" "F.Paste")
			(net "GND")
		)
		(pad "86" smd rect
			(at -2.050034 14.025118 270)
			(size 0.519938 1.4986)
			(layers "F.Cu" "F.Mask" "F.Paste")
			(net "M_E_CPU0_SA_RSP<1>")
		)
		(pad "87" smd rect
			(at -2.050034 14.875002 270)
			(size 0.519938 1.4986)
			(layers "F.Cu" "F.Mask" "F.Paste")
			(net "M_E_CPU0_SB_RSP<1>")
		)
		(pad "88" smd rect
			(at -2.050034 15.724886 270)
			(size 0.519938 1.4986)
			(layers "F.Cu" "F.Mask" "F.Paste")
			(net "GND")
		)
		(pad "89" smd rect
			(at -2.050034 16.575024 270)
			(size 0.519938 1.4986)
			(layers "F.Cu" "F.Mask" "F.Paste")
			(net "M_E_CPU0_SB_CB<4>")
		)
		(pad "90" smd rect
			(at -2.050034 17.424908 270)
			(size 0.519938 1.4986)
			(layers "F.Cu" "F.Mask" "F.Paste")
			(net "GND")
		)
		(pad "91" smd rect
			(at -2.050034 18.275046 270)
			(size 0.519938 1.4986)
			(layers "F.Cu" "F.Mask" "F.Paste")
			(net "M_E_CPU0_SB_CB<5>")
		)
	)
)
